(kicad_pcb
	(version 20260206)
	(generator "pcbnew")
	(generator_version "10.0")
	(general
		(thickness 1.6)
		(legacy_teardrops no)
	)
	(paper "A4")
	(title_block
		(title "03242023_DA0F0TMBIJ0_F0T_Motherboard_J_brd_V01_OCP.brd")
		(comment 1 "Grand Teton / footprints 2306-2312 of 6105")
	)
	(layers
		(0 "F.Cu" signal "TOP")
		(4 "In1.Cu" signal "GND")
		(6 "In2.Cu" signal "IN1")
		(8 "In3.Cu" signal "GND1")
		(10 "In4.Cu" signal "IN2")
		(12 "In5.Cu" signal "GND2")
		(14 "In6.Cu" signal "IN3")
		(16 "In7.Cu" signal "GND3")
		(18 "In8.Cu" signal "VCC")
		(20 "In9.Cu" signal "VCC1")
		(22 "In10.Cu" signal "GND4")
		(24 "In11.Cu" signal "IN4")
		(26 "In12.Cu" signal "GND5")
		(28 "In13.Cu" signal "IN5")
		(30 "In14.Cu" signal "GND6")
		(32 "In15.Cu" signal "IN6")
		(34 "In16.Cu" signal "GND7")
		(2 "B.Cu" signal "BOTTOM")
		(9 "F.Adhes" user "F.Adhesive")
		(11 "B.Adhes" user "B.Adhesive")
		(13 "F.Paste" user "Package Geometry/Pastemask Top")
		(15 "B.Paste" user "Package Geometry/Pastemask Bottom")
		(5 "F.SilkS" user "Ref Des/Silkscreen Top")
		(7 "B.SilkS" user "Ref Des/Silkscreen Bottom")
		(1 "F.Mask" user "Board Geometry/Soldermask Top")
		(3 "B.Mask" user "Board Geometry/Soldermask Bottom")
		(17 "Dwgs.User" user "User.Drawings")
		(19 "Cmts.User" user "User.Comments")
		(21 "Eco1.User" user "User.Eco1")
		(23 "Eco2.User" user "User.Eco2")
		(25 "Edge.Cuts" user "Board Geometry/Outline")
		(27 "Margin" user)
		(31 "F.CrtYd" user "Package Geometry/Place Bound Top")
		(29 "B.CrtYd" user "Package Geometry/Place Bound Bottom")
		(35 "F.Fab" user "Ref Des/Assembly Top")
		(33 "B.Fab" user "Ref Des/Assembly Bottom")
	)
	(footprint ""
		(layer "F.Cu")
		(at 31.937452 -161.582862 180)
		(property "Reference" "PR203"
			(at 0 0 180)
			(layer "F.SilkS")
			(hide yes)
			(effects
				(font
					(size 1.27 1.27)
				)
			)
		)
		(property "Value" ""
			(at 0 0 180)
			(layer "F.Fab")
			(effects
				(font
					(size 1.27 1.27)
				)
			)
		)
		(duplicate_pad_numbers_are_jumpers no)
		(fp_line
			(start 0.7874 0.4064)
			(end -0.7874 0.4064)
			(stroke
				(width 0.1524)
				(type default)
			)
			(layer "F.SilkS")
		)
		(fp_line
			(start 0.7874 -0.4064)
			(end 0.7874 0.4064)
			(stroke
				(width 0.1524)
				(type default)
			)
			(layer "F.SilkS")
		)
		(fp_line
			(start -0.7874 0.4064)
			(end -0.7874 -0.4064)
			(stroke
				(width 0.1524)
				(type default)
			)
			(layer "F.SilkS")
		)
		(fp_line
			(start -0.7874 -0.4064)
			(end 0.7874 -0.4064)
			(stroke
				(width 0.1524)
				(type default)
			)
			(layer "F.SilkS")
		)
		(fp_line
			(start 0.67945 0.3048)
			(end 0.120396 0.3048)
			(stroke
				(width 0.1)
				(type default)
			)
			(layer "F.Fab")
		)
		(fp_line
			(start 0.67945 -0.3048)
			(end 0.67945 0.3048)
			(stroke
				(width 0.1)
				(type default)
			)
			(layer "F.Fab")
		)
		(fp_line
			(start 0.12065 -0.2794)
			(end 0.12065 -0.3048)
			(stroke
				(width 0.1)
				(type default)
			)
			(layer "F.Fab")
		)
		(fp_line
			(start 0.12065 -0.3048)
			(end 0.67945 -0.3048)
			(stroke
				(width 0.1)
				(type default)
			)
			(layer "F.Fab")
		)
		(fp_line
			(start 0.120396 0.3048)
			(end 0.120396 0.2794)
			(stroke
				(width 0.1)
				(type default)
			)
			(layer "F.Fab")
		)
		(fp_line
			(start 0.120396 0.2794)
			(end -0.12065 0.2794)
			(stroke
				(width 0.1)
				(type default)
			)
			(layer "F.Fab")
		)
		(fp_line
			(start -0.12065 0.3048)
			(end -0.67945 0.3048)
			(stroke
				(width 0.1)
				(type default)
			)
			(layer "F.Fab")
		)
		(fp_line
			(start -0.12065 0.2794)
			(end -0.12065 0.3048)
			(stroke
				(width 0.1)
				(type default)
			)
			(layer "F.Fab")
		)
		(fp_line
			(start -0.12065 -0.2794)
			(end 0.12065 -0.2794)
			(stroke
				(width 0.1)
				(type default)
			)
			(layer "F.Fab")
		)
		(fp_line
			(start -0.12065 -0.305054)
			(end -0.12065 -0.2794)
			(stroke
				(width 0.1)
				(type default)
			)
			(layer "F.Fab")
		)
		(fp_line
			(start -0.67945 0.3048)
			(end -0.67945 -0.305054)
			(stroke
				(width 0.1)
				(type default)
			)
			(layer "F.Fab")
		)
		(fp_line
			(start -0.67945 -0.305054)
			(end -0.12065 -0.305054)
			(stroke
				(width 0.1)
				(type default)
			)
			(layer "F.Fab")
		)
		(pad "1" smd circle
			(at -0.40005 0 180)
			(size 0 0)
			(layers "F.Cu" "F.Mask" "F.Paste")
			(net "GND")
		)
		(pad "2" smd circle
			(at 0.40005 0 180)
			(size 0 0)
			(layers "F.Cu" "F.Mask" "F.Paste")
			(net "PVCCD_HV_CPU1_ADDR")
		)
	)
	(footprint ""
		(layer "F.Cu")
		(at 323.248528 -402.371052 -90)
		(property "Reference" "C1567"
			(at 0 0 270)
			(layer "F.SilkS")
			(hide yes)
			(effects
				(font
					(size 1.27 1.27)
				)
			)
		)
		(property "Value" ""
			(at 0 0 270)
			(layer "F.Fab")
			(effects
				(font
					(size 1.27 1.27)
				)
			)
		)
		(duplicate_pad_numbers_are_jumpers no)
		(fp_line
			(start -0.299974 0.150114)
			(end -0.299974 -0.150114)
			(stroke
				(width 0.1)
				(type default)
			)
			(layer "F.Fab")
		)
		(fp_line
			(start 0.299974 0.150114)
			(end -0.299974 0.150114)
			(stroke
				(width 0.1)
				(type default)
			)
			(layer "F.Fab")
		)
		(fp_line
			(start -0.299974 -0.150114)
			(end 0.299974 -0.150114)
			(stroke
				(width 0.1)
				(type default)
			)
			(layer "F.Fab")
		)
		(fp_line
			(start 0.299974 -0.150114)
			(end 0.299974 0.150114)
			(stroke
				(width 0.1)
				(type default)
			)
			(layer "F.Fab")
		)
		(pad "1" smd rect
			(at -0.2667 0 270)
			(size 0.3048 0.381)
			(layers "F.Cu" "F.Mask" "F.Paste")
			(net "P5E_CPU0_PE4_TX_C_DP<6>")
		)
		(pad "2" smd rect
			(at 0.2667 0 270)
			(size 0.3048 0.381)
			(layers "F.Cu" "F.Mask" "F.Paste")
			(net "P5E_CPU0_PE4_TX_DP<6>")
		)
	)
	(footprint ""
		(layer "F.Cu")
		(at 131.466844 -129.913126 180)
		(property "Reference" "R652"
			(at 0 0 180)
			(layer "F.SilkS")
			(hide yes)
			(effects
				(font
					(size 1.27 1.27)
				)
			)
		)
		(property "Value" ""
			(at 0 0 180)
			(layer "F.Fab")
			(effects
				(font
					(size 1.27 1.27)
				)
			)
		)
		(duplicate_pad_numbers_are_jumpers no)
		(fp_line
			(start 0.7874 0.4064)
			(end -0.7874 0.4064)
			(stroke
				(width 0.1524)
				(type default)
			)
			(layer "F.SilkS")
		)
		(fp_line
			(start 0.7874 -0.4064)
			(end 0.7874 0.4064)
			(stroke
				(width 0.1524)
				(type default)
			)
			(layer "F.SilkS")
		)
		(fp_line
			(start -0.7874 0.4064)
			(end -0.7874 -0.4064)
			(stroke
				(width 0.1524)
				(type default)
			)
			(layer "F.SilkS")
		)
		(fp_line
			(start -0.7874 -0.4064)
			(end 0.7874 -0.4064)
			(stroke
				(width 0.1524)
				(type default)
			)
			(layer "F.SilkS")
		)
		(fp_line
			(start 0.67945 0.3048)
			(end 0.120396 0.3048)
			(stroke
				(width 0.1)
				(type default)
			)
			(layer "F.Fab")
		)
		(fp_line
			(start 0.67945 -0.3048)
			(end 0.67945 0.3048)
			(stroke
				(width 0.1)
				(type default)
			)
			(layer "F.Fab")
		)
		(fp_line
			(start 0.12065 -0.2794)
			(end 0.12065 -0.3048)
			(stroke
				(width 0.1)
				(type default)
			)
			(layer "F.Fab")
		)
		(fp_line
			(start 0.12065 -0.3048)
			(end 0.67945 -0.3048)
			(stroke
				(width 0.1)
				(type default)
			)
			(layer "F.Fab")
		)
		(fp_line
			(start 0.120396 0.3048)
			(end 0.120396 0.2794)
			(stroke
				(width 0.1)
				(type default)
			)
			(layer "F.Fab")
		)
		(fp_line
			(start 0.120396 0.2794)
			(end -0.12065 0.2794)
			(stroke
				(width 0.1)
				(type default)
			)
			(layer "F.Fab")
		)
		(fp_line
			(start -0.12065 0.3048)
			(end -0.67945 0.3048)
			(stroke
				(width 0.1)
				(type default)
			)
			(layer "F.Fab")
		)
		(fp_line
			(start -0.12065 0.2794)
			(end -0.12065 0.3048)
			(stroke
				(width 0.1)
				(type default)
			)
			(layer "F.Fab")
		)
		(fp_line
			(start -0.12065 -0.2794)
			(end 0.12065 -0.2794)
			(stroke
				(width 0.1)
				(type default)
			)
			(layer "F.Fab")
		)
		(fp_line
			(start -0.12065 -0.305054)
			(end -0.12065 -0.2794)
			(stroke
				(width 0.1)
				(type default)
			)
			(layer "F.Fab")
		)
		(fp_line
			(start -0.67945 0.3048)
			(end -0.67945 -0.305054)
			(stroke
				(width 0.1)
				(type default)
			)
			(layer "F.Fab")
		)
		(fp_line
			(start -0.67945 -0.305054)
			(end -0.12065 -0.305054)
			(stroke
				(width 0.1)
				(type default)
			)
			(layer "F.Fab")
		)
		(pad "1" smd circle
			(at -0.40005 0 180)
			(size 0 0)
			(layers "F.Cu" "F.Mask" "F.Paste")
			(net "P3V3_AUX")
		)
		(pad "2" smd circle
			(at 0.40005 0 180)
			(size 0 0)
			(layers "F.Cu" "F.Mask" "F.Paste")
			(net "SMB_FRU_3V3AUX_SDA")
		)
	)
	(footprint ""
		(layer "F.Cu")
		(at 203.326492 -105.315004 -90)
		(property "Reference" "R1840"
			(at 0 0 270)
			(layer "F.SilkS")
			(hide yes)
			(effects
				(font
					(size 1.27 1.27)
				)
			)
		)
		(property "Value" ""
			(at 0 0 270)
			(layer "F.Fab")
			(effects
				(font
					(size 1.27 1.27)
				)
			)
		)
		(duplicate_pad_numbers_are_jumpers no)
		(fp_line
			(start -0.7874 0.4064)
			(end -0.7874 -0.4064)
			(stroke
				(width 0.1524)
				(type default)
			)
			(layer "F.SilkS")
		)
		(fp_line
			(start 0.7874 0.4064)
			(end -0.7874 0.4064)
			(stroke
				(width 0.1524)
				(type default)
			)
			(layer "F.SilkS")
		)
		(fp_line
			(start -0.7874 -0.4064)
			(end 0.7874 -0.4064)
			(stroke
				(width 0.1524)
				(type default)
			)
			(layer "F.SilkS")
		)
		(fp_line
			(start 0.7874 -0.4064)
			(end 0.7874 0.4064)
			(stroke
				(width 0.1524)
				(type default)
			)
			(layer "F.SilkS")
		)
		(fp_line
			(start -0.67945 0.3048)
			(end -0.67945 -0.305054)
			(stroke
				(width 0.1)
				(type default)
			)
			(layer "F.Fab")
		)
		(fp_line
			(start -0.12065 0.3048)
			(end -0.67945 0.3048)
			(stroke
				(width 0.1)
				(type default)
			)
			(layer "F.Fab")
		)
		(fp_line
			(start 0.120396 0.3048)
			(end 0.120396 0.2794)
			(stroke
				(width 0.1)
				(type default)
			)
			(layer "F.Fab")
		)
		(fp_line
			(start 0.67945 0.3048)
			(end 0.120396 0.3048)
			(stroke
				(width 0.1)
				(type default)
			)
			(layer "F.Fab")
		)
		(fp_line
			(start -0.12065 0.2794)
			(end -0.12065 0.3048)
			(stroke
				(width 0.1)
				(type default)
			)
			(layer "F.Fab")
		)
		(fp_line
			(start 0.120396 0.2794)
			(end -0.12065 0.2794)
			(stroke
				(width 0.1)
				(type default)
			)
			(layer "F.Fab")
		)
		(fp_line
			(start -0.12065 -0.2794)
			(end 0.12065 -0.2794)
			(stroke
				(width 0.1)
				(type default)
			)
			(layer "F.Fab")
		)
		(fp_line
			(start 0.12065 -0.2794)
			(end 0.12065 -0.3048)
			(stroke
				(width 0.1)
				(type default)
			)
			(layer "F.Fab")
		)
		(fp_line
			(start 0.12065 -0.3048)
			(end 0.67945 -0.3048)
			(stroke
				(width 0.1)
				(type default)
			)
			(layer "F.Fab")
		)
		(fp_line
			(start 0.67945 -0.3048)
			(end 0.67945 0.3048)
			(stroke
				(width 0.1)
				(type default)
			)
			(layer "F.Fab")
		)
		(fp_line
			(start -0.67945 -0.305054)
			(end -0.12065 -0.305054)
			(stroke
				(width 0.1)
				(type default)
			)
			(layer "F.Fab")
		)
		(fp_line
			(start -0.12065 -0.305054)
			(end -0.12065 -0.2794)
			(stroke
				(width 0.1)
				(type default)
			)
			(layer "F.Fab")
		)
		(pad "1" smd circle
			(at -0.40005 0 270)
			(size 0 0)
			(layers "F.Cu" "F.Mask" "F.Paste")
			(net "RST_PFR_OVR_SRTC")
		)
		(pad "2" smd circle
			(at 0.40005 0 270)
			(size 0 0)
			(layers "F.Cu" "F.Mask" "F.Paste")
			(net "RST_SRTCRST_N")
		)
	)
	(footprint ""
		(layer "F.Cu")
		(at 483.210108 -427.547024 180)
		(property "Reference" "DB8"
			(at -2.931668 -0.465836 90)
			(unlocked yes)
			(layer "F.SilkS")
			(effects
				(font
					(size 0.7874 0.5842)
					(thickness 0.1524)
				)
				(justify left)
			)
		)
		(property "Value" ""
			(at 0 0 180)
			(layer "F.Fab")
			(effects
				(font
					(size 1.27 1.27)
				)
			)
		)
		(duplicate_pad_numbers_are_jumpers no)
		(fp_line
			(start 2.71653 -3.151378)
			(end 0 4.011168)
			(stroke
				(width 0.1524)
				(type default)
			)
			(layer "F.SilkS")
		)
		(fp_line
			(start 0 4.011168)
			(end -3.330702 -4.771136)
			(stroke
				(width 0.1524)
				(type default)
			)
			(layer "F.SilkS")
		)
		(fp_line
			(start -3.330702 -4.771136)
			(end 3.330702 -4.771136)
			(stroke
				(width 0.1524)
				(type default)
			)
			(layer "F.SilkS")
		)
		(fp_line
			(start 3.330702 -4.771136)
			(end 0 4.011168)
			(stroke
				(width 0.1)
				(type default)
			)
			(layer "F.Fab")
		)
		(fp_line
			(start 0 4.011168)
			(end -3.330702 -4.771136)
			(stroke
				(width 0.1)
				(type default)
			)
			(layer "F.Fab")
		)
		(fp_line
			(start -3.330702 -4.771136)
			(end 3.330702 -4.771136)
			(stroke
				(width 0.1)
				(type default)
			)
			(layer "F.Fab")
		)
		(pad "1" thru_hole circle
			(at 0 0 180)
			(size 2.159 2.159)
			(drill 1.7018)
			(layers "*.Cu" "*.Mask")
			(remove_unused_layers no)
			(net "T1_GND")
			(clearance 0.0254)
			(thermal_gap 0.0254)
		)
		(pad "2" thru_hole circle
			(at -1.27 -3.348736 180)
			(size 2.159 2.159)
			(drill 1.7018)
			(layers "*.Cu" "*.Mask")
			(remove_unused_layers no)
			(net "TDR_SE_50_OHM_IN1")
			(clearance 0.0254)
			(thermal_gap 0.0254)
		)
		(pad "3" thru_hole circle
			(at 1.27 -3.348736 180)
			(size 2.159 2.159)
			(drill 1.7018)
			(layers "*.Cu" "*.Mask")
			(remove_unused_layers no)
			(net "TDR_SE_50_OHM_IN1")
			(clearance 0.0254)
			(thermal_gap 0.0254)
		)
	)
	(footprint ""
		(layer "F.Cu")
		(at 44.905422 -401.567396 90)
		(property "Reference" "R2656"
			(at 0 0 90)
			(layer "F.SilkS")
			(hide yes)
			(effects
				(font
					(size 1.27 1.27)
				)
			)
		)
		(property "Value" ""
			(at 0 0 90)
			(layer "F.Fab")
			(effects
				(font
					(size 1.27 1.27)
				)
			)
		)
		(duplicate_pad_numbers_are_jumpers no)
		(fp_line
			(start 0.7874 -0.4064)
			(end 0.7874 0.4064)
			(stroke
				(width 0.1524)
				(type default)
			)
			(layer "F.SilkS")
		)
		(fp_line
			(start -0.7874 -0.4064)
			(end 0.7874 -0.4064)
			(stroke
				(width 0.1524)
				(type default)
			)
			(layer "F.SilkS")
		)
		(fp_line
			(start 0.7874 0.4064)
			(end -0.7874 0.4064)
			(stroke
				(width 0.1524)
				(type default)
			)
			(layer "F.SilkS")
		)
		(fp_line
			(start -0.7874 0.4064)
			(end -0.7874 -0.4064)
			(stroke
				(width 0.1524)
				(type default)
			)
			(layer "F.SilkS")
		)
		(fp_line
			(start -0.12065 -0.305054)
			(end -0.12065 -0.2794)
			(stroke
				(width 0.1)
				(type default)
			)
			(layer "F.Fab")
		)
		(fp_line
			(start -0.67945 -0.305054)
			(end -0.12065 -0.305054)
			(stroke
				(width 0.1)
				(type default)
			)
			(layer "F.Fab")
		)
		(fp_line
			(start 0.67945 -0.3048)
			(end 0.67945 0.3048)
			(stroke
				(width 0.1)
				(type default)
			)
			(layer "F.Fab")
		)
		(fp_line
			(start 0.12065 -0.3048)
			(end 0.67945 -0.3048)
			(stroke
				(width 0.1)
				(type default)
			)
			(layer "F.Fab")
		)
		(fp_line
			(start 0.12065 -0.2794)
			(end 0.12065 -0.3048)
			(stroke
				(width 0.1)
				(type default)
			)
			(layer "F.Fab")
		)
		(fp_line
			(start -0.12065 -0.2794)
			(end 0.12065 -0.2794)
			(stroke
				(width 0.1)
				(type default)
			)
			(layer "F.Fab")
		)
		(fp_line
			(start 0.120396 0.2794)
			(end -0.12065 0.2794)
			(stroke
				(width 0.1)
				(type default)
			)
			(layer "F.Fab")
		)
		(fp_line
			(start -0.12065 0.2794)
			(end -0.12065 0.3048)
			(stroke
				(width 0.1)
				(type default)
			)
			(layer "F.Fab")
		)
		(fp_line
			(start 0.67945 0.3048)
			(end 0.120396 0.3048)
			(stroke
				(width 0.1)
				(type default)
			)
			(layer "F.Fab")
		)
		(fp_line
			(start 0.120396 0.3048)
			(end 0.120396 0.2794)
			(stroke
				(width 0.1)
				(type default)
			)
			(layer "F.Fab")
		)
		(fp_line
			(start -0.12065 0.3048)
			(end -0.67945 0.3048)
			(stroke
				(width 0.1)
				(type default)
			)
			(layer "F.Fab")
		)
		(fp_line
			(start -0.67945 0.3048)
			(end -0.67945 -0.305054)
			(stroke
				(width 0.1)
				(type default)
			)
			(layer "F.Fab")
		)
		(pad "1" smd circle
			(at -0.40005 0 90)
			(size 0 0)
			(layers "F.Cu" "F.Mask" "F.Paste")
			(net "HGX_DETECT_N_ISO")
		)
		(pad "2" smd circle
			(at 0.40005 0 90)
			(size 0 0)
			(layers "F.Cu" "F.Mask" "F.Paste")
			(net "GND")
		)
	)
	(footprint ""
		(layer "F.Cu")
		(at 139.02182 -92.644468 -90)
		(property "Reference" "R4050"
			(at 0 0 270)
			(layer "F.SilkS")
			(hide yes)
			(effects
				(font
					(size 1.27 1.27)
				)
			)
		)
		(property "Value" ""
			(at 0 0 270)
			(layer "F.Fab")
			(effects
				(font
					(size 1.27 1.27)
				)
			)
		)
		(duplicate_pad_numbers_are_jumpers no)
		(fp_line
			(start -0.7874 0.4064)
			(end -0.7874 -0.4064)
			(stroke
				(width 0.1524)
				(type default)
			)
			(layer "F.SilkS")
		)
		(fp_line
			(start 0.7874 0.4064)
			(end -0.7874 0.4064)
			(stroke
				(width 0.1524)
				(type default)
			)
			(layer "F.SilkS")
		)
		(fp_line
			(start -0.7874 -0.4064)
			(end 0.7874 -0.4064)
			(stroke
				(width 0.1524)
				(type default)
			)
			(layer "F.SilkS")
		)
		(fp_line
			(start 0.7874 -0.4064)
			(end 0.7874 0.4064)
			(stroke
				(width 0.1524)
				(type default)
			)
			(layer "F.SilkS")
		)
		(fp_line
			(start -0.67945 0.3048)
			(end -0.67945 -0.305054)
			(stroke
				(width 0.1)
				(type default)
			)
			(layer "F.Fab")
		)
		(fp_line
			(start -0.12065 0.3048)
			(end -0.67945 0.3048)
			(stroke
				(width 0.1)
				(type default)
			)
			(layer "F.Fab")
		)
		(fp_line
			(start 0.120396 0.3048)
			(end 0.120396 0.2794)
			(stroke
				(width 0.1)
				(type default)
			)
			(layer "F.Fab")
		)
		(fp_line
			(start 0.67945 0.3048)
			(end 0.120396 0.3048)
			(stroke
				(width 0.1)
				(type default)
			)
			(layer "F.Fab")
		)
		(fp_line
			(start -0.12065 0.2794)
			(end -0.12065 0.3048)
			(stroke
				(width 0.1)
				(type default)
			)
			(layer "F.Fab")
		)
		(fp_line
			(start 0.120396 0.2794)
			(end -0.12065 0.2794)
			(stroke
				(width 0.1)
				(type default)
			)
			(layer "F.Fab")
		)
		(fp_line
			(start -0.12065 -0.2794)
			(end 0.12065 -0.2794)
			(stroke
				(width 0.1)
				(type default)
			)
			(layer "F.Fab")
		)
		(fp_line
			(start 0.12065 -0.2794)
			(end 0.12065 -0.3048)
			(stroke
				(width 0.1)
				(type default)
			)
			(layer "F.Fab")
		)
		(fp_line
			(start 0.12065 -0.3048)
			(end 0.67945 -0.3048)
			(stroke
				(width 0.1)
				(type default)
			)
			(layer "F.Fab")
		)
		(fp_line
			(start 0.67945 -0.3048)
			(end 0.67945 0.3048)
			(stroke
				(width 0.1)
				(type default)
			)
			(layer "F.Fab")
		)
		(fp_line
			(start -0.67945 -0.305054)
			(end -0.12065 -0.305054)
			(stroke
				(width 0.1)
				(type default)
			)
			(layer "F.Fab")
		)
		(fp_line
			(start -0.12065 -0.305054)
			(end -0.12065 -0.2794)
			(stroke
				(width 0.1)
				(type default)
			)
			(layer "F.Fab")
		)
		(pad "1" smd circle
			(at -0.40005 0 270)
			(size 0 0)
			(layers "F.Cu" "F.Mask" "F.Paste")
			(net "H_CPU_ERR0_LVC2_R_N")
		)
		(pad "2" smd circle
			(at 0.40005 0 270)
			(size 0 0)
			(layers "F.Cu" "F.Mask" "F.Paste")
			(net "H_CPU_ERR0_LVC2_N")
		)
	)
)
